# T6G (Grand Teton) — schematic netlist excerpt (pin names and nets, part order shuffled) for the footprints in the layout excerpt that follows; sources: Cadence DE-HDL packaged netlist, KiCad conversion of 04192023_DAF0TMB3IC0_F0TG_MB_C_brd_V02_OCP.brd

PL6504  Q_INDUCTOR  100NH/16A IND  pkg SMLF  page 363 : \1\ = SW_P12V_AUX_P0V9_RETIMER_CPU0_FLT ; \2\ = P12V_AUX
C1574  Q_CAP_DIFFBUS  DIFF BUS_0.22UF 6.3V 20% X6S  pkg C0201  page 65 : \1\ = P5E_CPU0_G3_TX_C_DN<2> ; \2\ = P5E_CPU0_G3_TX_DN<2>
R1002  Q_RES  0 5% EMPTY  pkg 0402LF  page 290 : A = P1V8_CPU0_RT1_1A_1D ; B = P1V8_CPU0_RT1_1A

(kicad_pcb
	(version 20260206)
	(generator "pcbnew")
	(generator_version "10.0")
	(general
		(thickness 1.6)
		(legacy_teardrops no)
	)
	(paper "A4")
	(title_block
		(title "04192023_DAF0TMB3IC0_F0TG_MB_C_brd_V02_OCP.brd")
		(comment 1 "Grand Teton / footprints 148-150 of 8354")
	)
	(layers
		(0 "F.Cu" signal "TOP")
		(4 "In1.Cu" signal "GND")
		(6 "In2.Cu" signal "IN1")
		(8 "In3.Cu" signal "GND1")
		(10 "In4.Cu" signal "IN2")
		(12 "In5.Cu" signal "GND2")
		(14 "In6.Cu" signal "IN3")
		(16 "In7.Cu" signal "GND3")
		(18 "In8.Cu" signal "VCC")
		(20 "In9.Cu" signal "VCC1")
		(22 "In10.Cu" signal "GND4")
		(24 "In11.Cu" signal "IN4")
		(26 "In12.Cu" signal "GND5")
		(28 "In13.Cu" signal "IN5")
		(30 "In14.Cu" signal "GND6")
		(32 "In15.Cu" signal "IN6")
		(34 "In16.Cu" signal "GND7")
		(2 "B.Cu" signal "BOTTOM")
		(9 "F.Adhes" user "F.Adhesive")
		(11 "B.Adhes" user "B.Adhesive")
		(13 "F.Paste" user "Package Geometry/Pastemask Top")
		(15 "B.Paste" user "Package Geometry/Pastemask Bottom")
		(5 "F.SilkS" user "Ref Des/Silkscreen Top")
		(7 "B.SilkS" user "Ref Des/Silkscreen Bottom")
		(1 "F.Mask" user "Board Geometry/Soldermask Top")
		(3 "B.Mask" user "Board Geometry/Soldermask Bottom")
		(17 "Dwgs.User" user "User.Drawings")
		(19 "Cmts.User" user "User.Comments")
		(21 "Eco1.User" user "User.Eco1")
		(23 "Eco2.User" user "User.Eco2")
		(25 "Edge.Cuts" user "Board Geometry/Outline")
		(27 "Margin" user)
		(31 "F.CrtYd" user "Package Geometry/Place Bound Top")
		(29 "B.CrtYd" user "Package Geometry/Place Bound Bottom")
		(35 "F.Fab" user "Ref Des/Assembly Top")
		(33 "B.Fab" user "Ref Des/Assembly Bottom")
	)
	(footprint ""
		(layer "F.Cu")
		(at 358.389936 -393.47648 180)
		(property "Reference" "R1002"
			(at 0 0 180)
			(layer "F.SilkS")
			(hide yes)
			(effects
				(font
					(size 1.27 1.27)
				)
			)
		)
		(property "Value" ""
			(at 0 0 180)
			(layer "F.Fab")
			(effects
				(font
					(size 1.27 1.27)
				)
			)
		)
		(duplicate_pad_numbers_are_jumpers no)
		(fp_line
			(start 0.7874 0.4064)
			(end -0.7874 0.4064)
			(stroke
				(width 0.1524)
				(type default)
			)
			(layer "F.SilkS")
		)
		(fp_line
			(start 0.7874 -0.4064)
			(end 0.7874 0.4064)
			(stroke
				(width 0.1524)
				(type default)
			)
			(layer "F.SilkS")
		)
		(fp_line
			(start -0.7874 0.4064)
			(end -0.7874 -0.4064)
			(stroke
				(width 0.1524)
				(type default)
			)
			(layer "F.SilkS")
		)
		(fp_line
			(start -0.7874 -0.4064)
			(end 0.7874 -0.4064)
			(stroke
				(width 0.1524)
				(type default)
			)
			(layer "F.SilkS")
		)
		(fp_line
			(start 0.67945 0.3048)
			(end 0.120396 0.3048)
			(stroke
				(width 0.1)
				(type default)
			)
			(layer "F.Fab")
		)
		(fp_line
			(start 0.67945 -0.3048)
			(end 0.67945 0.3048)
			(stroke
				(width 0.1)
				(type default)
			)
			(layer "F.Fab")
		)
		(fp_line
			(start 0.12065 -0.2794)
			(end 0.12065 -0.3048)
			(stroke
				(width 0.1)
				(type default)
			)
			(layer "F.Fab")
		)
		(fp_line
			(start 0.12065 -0.3048)
			(end 0.67945 -0.3048)
			(stroke
				(width 0.1)
				(type default)
			)
			(layer "F.Fab")
		)
		(fp_line
			(start 0.120396 0.3048)
			(end 0.120396 0.2794)
			(stroke
				(width 0.1)
				(type default)
			)
			(layer "F.Fab")
		)
		(fp_line
			(start 0.120396 0.2794)
			(end -0.12065 0.2794)
			(stroke
				(width 0.1)
				(type default)
			)
			(layer "F.Fab")
		)
		(fp_line
			(start -0.12065 0.3048)
			(end -0.67945 0.3048)
			(stroke
				(width 0.1)
				(type default)
			)
			(layer "F.Fab")
		)
		(fp_line
			(start -0.12065 0.2794)
			(end -0.12065 0.3048)
			(stroke
				(width 0.1)
				(type default)
			)
			(layer "F.Fab")
		)
		(fp_line
			(start -0.12065 -0.2794)
			(end 0.12065 -0.2794)
			(stroke
				(width 0.1)
				(type default)
			)
			(layer "F.Fab")
		)
		(fp_line
			(start -0.12065 -0.305054)
			(end -0.12065 -0.2794)
			(stroke
				(width 0.1)
				(type default)
			)
			(layer "F.Fab")
		)
		(fp_line
			(start -0.67945 0.3048)
			(end -0.67945 -0.305054)
			(stroke
				(width 0.1)
				(type default)
			)
			(layer "F.Fab")
		)
		(fp_line
			(start -0.67945 -0.305054)
			(end -0.12065 -0.305054)
			(stroke
				(width 0.1)
				(type default)
			)
			(layer "F.Fab")
		)
		(pad "1" smd rect
			(at -0.40005 0)
			(size 0.4572 0.508)
			(layers "F.Cu" "F.Mask" "F.Paste")
			(net "P1V8_CPU0_RT1_1A_1D")
		)
		(pad "2" smd rect
			(at 0.40005 0)
			(size 0.4572 0.508)
			(layers "F.Cu" "F.Mask" "F.Paste")
			(net "P1V8_CPU0_RT1_1A")
		)
	)
	(footprint ""
		(layer "F.Cu")
		(at 452.115174 -413.0167 90)
		(property "Reference" "PL6504"
			(at -3.72237 -2.281174 0)
			(unlocked yes)
			(layer "F.SilkS")
			(effects
				(font
					(size 0.7874 0.5842)
					(thickness 0.1524)
				)
				(justify left)
			)
		)
		(property "Value" ""
			(at 0 0 90)
			(layer "F.Fab")
			(effects
				(font
					(size 1.27 1.27)
				)
			)
		)
		(duplicate_pad_numbers_are_jumpers no)
		(fp_line
			(start 2.249932 -2.249932)
			(end 2.249932 -1.3843)
			(stroke
				(width 0.1524)
				(type default)
			)
			(layer "F.SilkS")
		)
		(fp_line
			(start -2.249932 -2.249932)
			(end 2.249932 -2.249932)
			(stroke
				(width 0.1524)
				(type default)
			)
			(layer "F.SilkS")
		)
		(fp_line
			(start -2.249932 -1.3843)
			(end -2.249932 -2.249932)
			(stroke
				(width 0.1524)
				(type default)
			)
			(layer "F.SilkS")
		)
		(fp_line
			(start 2.249932 1.3843)
			(end 2.249932 2.249932)
			(stroke
				(width 0.1524)
				(type default)
			)
			(layer "F.SilkS")
		)
		(fp_line
			(start 2.249932 2.249932)
			(end -2.249932 2.249932)
			(stroke
				(width 0.1524)
				(type default)
			)
			(layer "F.SilkS")
		)
		(fp_line
			(start -2.249932 2.249932)
			(end -2.249932 1.3843)
			(stroke
				(width 0.1524)
				(type default)
			)
			(layer "F.SilkS")
		)
		(fp_line
			(start 2.249932 -2.249932)
			(end 2.249932 2.249932)
			(stroke
				(width 0.1)
				(type default)
			)
			(layer "F.Fab")
		)
		(fp_line
			(start -2.249932 -2.249932)
			(end 2.249932 -2.249932)
			(stroke
				(width 0.1)
				(type default)
			)
			(layer "F.Fab")
		)
		(fp_line
			(start 2.249932 2.249932)
			(end -2.249932 2.249932)
			(stroke
				(width 0.1)
				(type default)
			)
			(layer "F.Fab")
		)
		(fp_line
			(start -2.249932 2.249932)
			(end -2.249932 -2.249932)
			(stroke
				(width 0.1)
				(type default)
			)
			(layer "F.Fab")
		)
		(pad "1" smd rect
			(at -1.82499 0 90)
			(size 1.0668 2.5146)
			(layers "F.Cu" "F.Mask" "F.Paste")
			(net "SW_P12V_AUX_P0V9_RETIMER_CPU0_FLT")
		)
		(pad "2" smd rect
			(at 1.82499 0 90)
			(size 1.0668 2.5146)
			(layers "F.Cu" "F.Mask" "F.Paste")
			(net "P12V_AUX")
		)
	)
	(footprint ""
		(layer "F.Cu")
		(at 426.6692 -17.624298 90)
		(property "Reference" "C1574"
			(at 0 0 90)
			(layer "F.SilkS")
			(hide yes)
			(effects
				(font
					(size 1.27 1.27)
				)
			)
		)
		(property "Value" ""
			(at 0 0 90)
			(layer "F.Fab")
			(effects
				(font
					(size 1.27 1.27)
				)
			)
		)
		(duplicate_pad_numbers_are_jumpers no)
		(fp_line
			(start 0.299974 -0.150114)
			(end 0.299974 0.150114)
			(stroke
				(width 0.1)
				(type default)
			)
			(layer "F.Fab")
		)
		(fp_line
			(start -0.299974 -0.150114)
			(end 0.299974 -0.150114)
			(stroke
				(width 0.1)
				(type default)
			)
			(layer "F.Fab")
		)
		(fp_line
			(start 0.299974 0.150114)
			(end -0.299974 0.150114)
			(stroke
				(width 0.1)
				(type default)
			)
			(layer "F.Fab")
		)
		(fp_line
			(start -0.299974 0.150114)
			(end -0.299974 -0.150114)
			(stroke
				(width 0.1)
				(type default)
			)
			(layer "F.Fab")
		)
		(pad "1" smd rect
			(at -0.2667 0 90)
			(size 0.3048 0.381)
			(layers "F.Cu" "F.Mask" "F.Paste")
			(net "P5E_CPU0_G3_TX_C_DN<2>")
		)
		(pad "2" smd rect
			(at 0.2667 0 90)
			(size 0.3048 0.381)
			(layers "F.Cu" "F.Mask" "F.Paste")
			(net "P5E_CPU0_G3_TX_DN<2>")
		)
	)
)
